# S9S_MB_2U (Grand Teton) — schematic netlist excerpt (pin names and nets, part order shuffled) for the footprints in the layout excerpt that follows; sources: Cadence DE-HDL packaged netlist, KiCad conversion of 03242023_DA0F0TMBIJ0_F0T_Motherboard_J_brd_V01_OCP.brd

R3663  Q_RES  10K 1% CHIP  pkg 0402LF  page 152 : A = P3V3_AUX ; B = USB_HUB_PSELF
C868  Q_CAP_DIFFBUS  DIFF BUS_0.22UF 6.3V 20% X6S  pkg C0201  page 174 : \1\ = P5E_CPU0_PE1_TX_C_DN<0> ; \2\ = P5E_CPU0_PE1_TX_DN<0>

U117  TPS3895ADRYR  EMPTY  pkg SON6  page 244
  ENABLE  = FM_COMP_P3V3_AUX_ENIN
  GND  = GND
  SENSE  = FM_COMP_P3V3_AUX_VIN
  SENSE_OUT  = PWRGD_DSW_PWROK_R1
  CT  = FM_COMP_P3V3_STBY_CEXT
  VCC  = P3V3_AUX

(kicad_pcb
	(version 20260206)
	(generator "pcbnew")
	(generator_version "10.0")
	(general
		(thickness 1.6)
		(legacy_teardrops no)
	)
	(paper "A4")
	(title_block
		(title "03242023_DA0F0TMBIJ0_F0T_Motherboard_J_brd_V01_OCP.brd")
		(comment 1 "Grand Teton / footprints 1374-1376 of 6105")
	)
	(layers
		(0 "F.Cu" signal "TOP")
		(4 "In1.Cu" signal "GND")
		(6 "In2.Cu" signal "IN1")
		(8 "In3.Cu" signal "GND1")
		(10 "In4.Cu" signal "IN2")
		(12 "In5.Cu" signal "GND2")
		(14 "In6.Cu" signal "IN3")
		(16 "In7.Cu" signal "GND3")
		(18 "In8.Cu" signal "VCC")
		(20 "In9.Cu" signal "VCC1")
		(22 "In10.Cu" signal "GND4")
		(24 "In11.Cu" signal "IN4")
		(26 "In12.Cu" signal "GND5")
		(28 "In13.Cu" signal "IN5")
		(30 "In14.Cu" signal "GND6")
		(32 "In15.Cu" signal "IN6")
		(34 "In16.Cu" signal "GND7")
		(2 "B.Cu" signal "BOTTOM")
		(9 "F.Adhes" user "F.Adhesive")
		(11 "B.Adhes" user "B.Adhesive")
		(13 "F.Paste" user "Package Geometry/Pastemask Top")
		(15 "B.Paste" user "Package Geometry/Pastemask Bottom")
		(5 "F.SilkS" user "Ref Des/Silkscreen Top")
		(7 "B.SilkS" user "Ref Des/Silkscreen Bottom")
		(1 "F.Mask" user "Board Geometry/Soldermask Top")
		(3 "B.Mask" user "Board Geometry/Soldermask Bottom")
		(17 "Dwgs.User" user "User.Drawings")
		(19 "Cmts.User" user "User.Comments")
		(21 "Eco1.User" user "User.Eco1")
		(23 "Eco2.User" user "User.Eco2")
		(25 "Edge.Cuts" user "Board Geometry/Outline")
		(27 "Margin" user)
		(31 "F.CrtYd" user "Package Geometry/Place Bound Top")
		(29 "B.CrtYd" user "Package Geometry/Place Bound Bottom")
		(35 "F.Fab" user "Ref Des/Assembly Top")
		(33 "B.Fab" user "Ref Des/Assembly Bottom")
	)
	(footprint ""
		(layer "F.Cu")
		(at 21.176996 -97.083626 180)
		(property "Reference" "R3663"
			(at 0 0 180)
			(layer "F.SilkS")
			(hide yes)
			(effects
				(font
					(size 1.27 1.27)
				)
			)
		)
		(property "Value" ""
			(at 0 0 180)
			(layer "F.Fab")
			(effects
				(font
					(size 1.27 1.27)
				)
			)
		)
		(duplicate_pad_numbers_are_jumpers no)
		(fp_line
			(start 0.7874 0.4064)
			(end -0.7874 0.4064)
			(stroke
				(width 0.1524)
				(type default)
			)
			(layer "F.SilkS")
		)
		(fp_line
			(start 0.7874 -0.4064)
			(end 0.7874 0.4064)
			(stroke
				(width 0.1524)
				(type default)
			)
			(layer "F.SilkS")
		)
		(fp_line
			(start -0.7874 0.4064)
			(end -0.7874 -0.4064)
			(stroke
				(width 0.1524)
				(type default)
			)
			(layer "F.SilkS")
		)
		(fp_line
			(start -0.7874 -0.4064)
			(end 0.7874 -0.4064)
			(stroke
				(width 0.1524)
				(type default)
			)
			(layer "F.SilkS")
		)
		(fp_line
			(start 0.67945 0.3048)
			(end 0.120396 0.3048)
			(stroke
				(width 0.1)
				(type default)
			)
			(layer "F.Fab")
		)
		(fp_line
			(start 0.67945 -0.3048)
			(end 0.67945 0.3048)
			(stroke
				(width 0.1)
				(type default)
			)
			(layer "F.Fab")
		)
		(fp_line
			(start 0.12065 -0.2794)
			(end 0.12065 -0.3048)
			(stroke
				(width 0.1)
				(type default)
			)
			(layer "F.Fab")
		)
		(fp_line
			(start 0.12065 -0.3048)
			(end 0.67945 -0.3048)
			(stroke
				(width 0.1)
				(type default)
			)
			(layer "F.Fab")
		)
		(fp_line
			(start 0.120396 0.3048)
			(end 0.120396 0.2794)
			(stroke
				(width 0.1)
				(type default)
			)
			(layer "F.Fab")
		)
		(fp_line
			(start 0.120396 0.2794)
			(end -0.12065 0.2794)
			(stroke
				(width 0.1)
				(type default)
			)
			(layer "F.Fab")
		)
		(fp_line
			(start -0.12065 0.3048)
			(end -0.67945 0.3048)
			(stroke
				(width 0.1)
				(type default)
			)
			(layer "F.Fab")
		)
		(fp_line
			(start -0.12065 0.2794)
			(end -0.12065 0.3048)
			(stroke
				(width 0.1)
				(type default)
			)
			(layer "F.Fab")
		)
		(fp_line
			(start -0.12065 -0.2794)
			(end 0.12065 -0.2794)
			(stroke
				(width 0.1)
				(type default)
			)
			(layer "F.Fab")
		)
		(fp_line
			(start -0.12065 -0.305054)
			(end -0.12065 -0.2794)
			(stroke
				(width 0.1)
				(type default)
			)
			(layer "F.Fab")
		)
		(fp_line
			(start -0.67945 0.3048)
			(end -0.67945 -0.305054)
			(stroke
				(width 0.1)
				(type default)
			)
			(layer "F.Fab")
		)
		(fp_line
			(start -0.67945 -0.305054)
			(end -0.12065 -0.305054)
			(stroke
				(width 0.1)
				(type default)
			)
			(layer "F.Fab")
		)
		(pad "1" smd circle
			(at -0.40005 0 180)
			(size 0 0)
			(layers "F.Cu" "F.Mask" "F.Paste")
			(net "P3V3_AUX")
		)
		(pad "2" smd circle
			(at 0.40005 0 180)
			(size 0 0)
			(layers "F.Cu" "F.Mask" "F.Paste")
			(net "USB_HUB_PSELF")
		)
	)
	(footprint ""
		(layer "F.Cu")
		(at 433.180236 -17.612614 90)
		(property "Reference" "C868"
			(at 0 0 90)
			(layer "F.SilkS")
			(hide yes)
			(effects
				(font
					(size 1.27 1.27)
				)
			)
		)
		(property "Value" ""
			(at 0 0 90)
			(layer "F.Fab")
			(effects
				(font
					(size 1.27 1.27)
				)
			)
		)
		(duplicate_pad_numbers_are_jumpers no)
		(fp_line
			(start 0.299974 -0.150114)
			(end 0.299974 0.150114)
			(stroke
				(width 0.1)
				(type default)
			)
			(layer "F.Fab")
		)
		(fp_line
			(start -0.299974 -0.150114)
			(end 0.299974 -0.150114)
			(stroke
				(width 0.1)
				(type default)
			)
			(layer "F.Fab")
		)
		(fp_line
			(start 0.299974 0.150114)
			(end -0.299974 0.150114)
			(stroke
				(width 0.1)
				(type default)
			)
			(layer "F.Fab")
		)
		(fp_line
			(start -0.299974 0.150114)
			(end -0.299974 -0.150114)
			(stroke
				(width 0.1)
				(type default)
			)
			(layer "F.Fab")
		)
		(pad "1" smd rect
			(at -0.2667 0 90)
			(size 0.3048 0.381)
			(layers "F.Cu" "F.Mask" "F.Paste")
			(net "P5E_CPU0_PE1_TX_C_DN<0>")
		)
		(pad "2" smd rect
			(at 0.2667 0 90)
			(size 0.3048 0.381)
			(layers "F.Cu" "F.Mask" "F.Paste")
			(net "P5E_CPU0_PE1_TX_DN<0>")
		)
	)
	(footprint ""
		(layer "F.Cu")
		(at 212.442806 -134.065518)
		(property "Reference" "U117"
			(at 1.884934 -1.66624 0)
			(unlocked yes)
			(layer "F.SilkS")
			(effects
				(font
					(size 0.7874 0.5842)
					(thickness 0.1524)
				)
			)
		)
		(property "Value" ""
			(at 0 0 0)
			(layer "F.Fab")
			(effects
				(font
					(size 1.27 1.27)
				)
			)
		)
		(duplicate_pad_numbers_are_jumpers no)
		(fp_line
			(start -0.779018 -0.800862)
			(end -0.779018 0.800862)
			(stroke
				(width 0.1524)
				(type default)
			)
			(layer "F.SilkS")
		)
		(fp_line
			(start -0.779018 0.800862)
			(end 0.779018 0.800862)
			(stroke
				(width 0.1524)
				(type default)
			)
			(layer "F.SilkS")
		)
		(fp_line
			(start 0.779018 -0.800862)
			(end -0.779018 -0.800862)
			(stroke
				(width 0.1524)
				(type default)
			)
			(layer "F.SilkS")
		)
		(fp_line
			(start 0.779018 0.800862)
			(end 0.779018 -0.800862)
			(stroke
				(width 0.1524)
				(type default)
			)
			(layer "F.SilkS")
		)
		(fp_poly
			(pts
				(xy -0.462534 -1.245108) (xy -0.677164 -1.634998) (xy -0.248158 -1.634998)
			)
			(stroke
				(width 0)
				(type default)
			)
			(fill yes)
			(layer "F.SilkS")
		)
		(fp_line
			(start -0.525018 -0.750062)
			(end 0.525018 -0.750062)
			(stroke
				(width 0.1)
				(type default)
			)
			(layer "F.Fab")
		)
		(fp_line
			(start -0.525018 0.750062)
			(end -0.525018 -0.750062)
			(stroke
				(width 0.1)
				(type default)
			)
			(layer "F.Fab")
		)
		(fp_line
			(start 0.525018 -0.750062)
			(end 0.525018 0.750062)
			(stroke
				(width 0.1)
				(type default)
			)
			(layer "F.Fab")
		)
		(fp_line
			(start 0.525018 0.750062)
			(end -0.525018 0.750062)
			(stroke
				(width 0.1)
				(type default)
			)
			(layer "F.Fab")
		)
		(fp_poly
			(pts
				(xy -0.923544 -0.500126) (xy -1.313434 -0.714502) (xy -1.313434 -0.285496)
			)
			(stroke
				(width 0)
				(type default)
			)
			(fill yes)
			(layer "F.Fab")
		)
		(pad "1" smd rect
			(at -0.377444 -0.500126 270)
			(size 0.3048 0.5334)
			(layers "F.Cu" "F.Mask" "F.Paste")
			(net "FM_COMP_P3V3_AUX_ENIN")
		)
		(pad "2" smd rect
			(at -0.372618 0 270)
			(size 0.2794 0.508)
			(layers "F.Cu" "F.Mask" "F.Paste")
			(net "GND")
		)
		(pad "3" smd rect
			(at -0.372618 0.499872 270)
			(size 0.2794 0.508)
			(layers "F.Cu" "F.Mask" "F.Paste")
			(net "FM_COMP_P3V3_AUX_VIN")
		)
		(pad "4" smd rect
			(at 0.377444 0.499872 270)
			(size 0.2794 0.508)
			(layers "F.Cu" "F.Mask" "F.Paste")
			(net "PWRGD_DSW_PWROK_R1")
		)
		(pad "5" smd rect
			(at 0.377444 0 270)
			(size 0.2794 0.508)
			(layers "F.Cu" "F.Mask" "F.Paste")
			(net "FM_COMP_P3V3_STBY_CEXT")
		)
		(pad "6" smd rect
			(at 0.377444 -0.500126 270)
			(size 0.2794 0.508)
			(layers "F.Cu" "F.Mask" "F.Paste")
			(net "P3V3_AUX")
		)
	)
)
